(kicad_pcb
	(version 20241229)
	(generator "pcbnew")
	(generator_version "9.0")
	(general
		(thickness 1.61)
		(legacy_teardrops no)
	)
	(paper "A3")
	(title_block
		(title "SO-DIMM DDR5 Tester")
		(date "2025-11-26")
		(rev "1.3.0")
		(comment 9 "footprints 115-117 of 627")
	)
	(layers
		(0 "F.Cu" signal)
		(4 "In1.Cu" power)
		(6 "In2.Cu" mixed)
		(8 "In3.Cu" power)
		(10 "In4.Cu" mixed)
		(12 "In5.Cu" power)
		(14 "In6.Cu" mixed)
		(16 "In7.Cu" power)
		(18 "In8.Cu" power)
		(20 "In9.Cu" mixed)
		(22 "In10.Cu" power)
		(2 "B.Cu" signal)
		(9 "F.Adhes" user "F.Adhesive")
		(11 "B.Adhes" user "B.Adhesive")
		(13 "F.Paste" user)
		(15 "B.Paste" user)
		(5 "F.SilkS" user "F.Silkscreen")
		(7 "B.SilkS" user "B.Silkscreen")
		(1 "F.Mask" user)
		(3 "B.Mask" user)
		(17 "Dwgs.User" user "User.Drawings")
		(19 "Cmts.User" user "User.Comments")
		(21 "Eco1.User" user "User.Eco1")
		(23 "Eco2.User" user "User.Eco2")
		(25 "Edge.Cuts" user)
		(27 "Margin" user)
		(31 "F.CrtYd" user "F.Courtyard")
		(29 "B.CrtYd" user "B.Courtyard")
		(35 "F.Fab" user)
		(33 "B.Fab" user)
	)
	(footprint "antmicro-footprints:SOT-23-5"
		(layer "F.Cu")
		(at 196.663499 135.49)
		(property "Reference" "U21"
			(at -2.363499 2.81 90)
			(layer "F.SilkS")
			(effects
				(font
					(size 0.7 0.7)
					(thickness 0.15)
				)
				(justify left bottom)
			)
		)
		(property "Value" "NCP718BSN330T1G"
			(at 0.002 2.799 0)
			(layer "F.Fab")
			(effects
				(font
					(size 0.7 0.7)
					(thickness 0.15)
				)
				(justify left bottom)
			)
		)
		(property "Datasheet" "https://www.mouser.com/datasheet/2/308/NCP718_D-1224359.pdf"
			(at 0 0 0)
			(layer "F.Fab")
			(hide yes)
			(effects
				(font
					(size 1.27 1.27)
					(thickness 0.15)
				)
			)
		)
		(property "Author" "Antmicro"
			(at 0 0 0)
			(layer "F.Fab")
			(hide yes)
			(effects
				(font
					(size 1 1)
					(thickness 0.15)
				)
			)
		)
		(property "License" "Apache-2.0"
			(at 0 0 0)
			(layer "F.Fab")
			(hide yes)
			(effects
				(font
					(size 1 1)
					(thickness 0.15)
				)
			)
		)
		(property "MPN" "NCP718BSN330T1G"
			(at 0 0 0)
			(layer "F.Fab")
			(hide yes)
			(effects
				(font
					(size 1 1)
					(thickness 0.15)
				)
			)
		)
		(property "Manufacturer" "ON Semiconductor"
			(at 0 0 0)
			(layer "F.Fab")
			(hide yes)
			(effects
				(font
					(size 1 1)
					(thickness 0.15)
				)
			)
		)
		(sheetname "/Supply/")
		(sheetfile "supply.kicad_sch")
		(attr smd)
		(fp_line
			(start -0.85 1.6)
			(end -0.85 1.301)
			(stroke
				(width 0.15)
				(type solid)
			)
			(layer "F.SilkS")
		)
		(fp_line
			(start -0.8 -1.6)
			(end -0.8 -1.3)
			(stroke
				(width 0.15)
				(type solid)
			)
			(layer "F.SilkS")
		)
		(fp_line
			(start -0.8 -1.6)
			(end -0.5 -1.6)
			(stroke
				(width 0.15)
				(type solid)
			)
			(layer "F.SilkS")
		)
		(fp_line
			(start -0.55 1.6)
			(end -0.85 1.6)
			(stroke
				(width 0.15)
				(type solid)
			)
			(layer "F.SilkS")
		)
		(fp_line
			(start 0.8 -1.6)
			(end 0.5 -1.6)
			(stroke
				(width 0.15)
				(type solid)
			)
			(layer "F.SilkS")
		)
		(fp_line
			(start 0.8 -1.3)
			(end 0.8 -1.6)
			(stroke
				(width 0.15)
				(type solid)
			)
			(layer "F.SilkS")
		)
		(fp_line
			(start 0.8 0.55)
			(end 0.8 -0.55)
			(stroke
				(width 0.15)
				(type solid)
			)
			(layer "F.SilkS")
		)
		(fp_line
			(start 0.8 1.3)
			(end 0.8 1.599)
			(stroke
				(width 0.15)
				(type solid)
			)
			(layer "F.SilkS")
		)
		(fp_line
			(start 0.8 1.599)
			(end 0.549 1.599)
			(stroke
				(width 0.15)
				(type solid)
			)
			(layer "F.SilkS")
		)
		(fp_circle
			(center -1.25 -1.5)
			(end -1.2 -1.5)
			(stroke
				(width 0.15)
				(type solid)
			)
			(fill yes)
			(layer "F.SilkS")
		)
		(fp_rect
			(start 1.9 -1.76)
			(end -1.9 1.75)
			(stroke
				(width 0.05)
				(type solid)
			)
			(fill no)
			(layer "F.CrtYd")
		)
		(fp_line
			(start -0.398 -1.526)
			(end -0.874 -1.05)
			(stroke
				(width 0.15)
				(type solid)
			)
			(layer "F.Fab")
		)
		(fp_rect
			(start 0.874 1.523)
			(end -0.873 -1.525)
			(stroke
				(width 0.15)
				(type solid)
			)
			(fill no)
			(layer "F.Fab")
		)
		(pad "1" smd rect
			(at -1.351 -0.951 270)
			(size 0.55 1)
			(layers "F.Cu" "F.Mask" "F.Paste")
			(net 38 "VDC")
			(pinfunction "VIN")
			(pintype "passive")
		)
		(pad "2" smd rect
			(at -1.351 0 270)
			(size 0.55 1)
			(layers "F.Cu" "F.Mask" "F.Paste")
			(net 1 "GND")
			(pinfunction "GND")
			(pintype "passive")
		)
		(pad "3" smd rect
			(at -1.351 0.949 270)
			(size 0.55 1)
			(layers "F.Cu" "F.Mask" "F.Paste")
			(net 38 "VDC")
			(pinfunction "EN")
			(pintype "passive")
		)
		(pad "4" smd rect
			(at 1.35 0.949 270)
			(size 0.55 1)
			(layers "F.Cu" "F.Mask" "F.Paste")
			(net 730 "unconnected-(U21-NC-Pad4)")
			(pinfunction "NC")
			(pintype "no_connect")
		)
		(pad "5" smd rect
			(at 1.35 -0.951 270)
			(size 0.55 1)
			(layers "F.Cu" "F.Mask" "F.Paste")
			(net 41 "+3V3_AON")
			(pinfunction "VOUT")
			(pintype "passive")
		)
	)
	(footprint "antmicro-footprints:C_0402_1005Metric"
		(layer "F.Cu")
		(at 107.251 180.584 -90)
		(descr "Capacitor SMD 0402")
		(tags "capacitor SMD 0402")
		(property "Reference" "C130"
			(at 0 -0.699 270)
			(layer "F.SilkS")
			(hide yes)
			(effects
				(font
					(size 0.7 0.7)
					(thickness 0.15)
				)
				(justify left bottom)
			)
		)
		(property "Value" "C_100n_0402"
			(at -1.022927 2.155213 270)
			(layer "F.Fab")
			(effects
				(font
					(size 0.7 0.7)
					(thickness 0.15)
				)
				(justify left bottom)
			)
		)
		(property "Datasheet" "https://www.murata.com/products/productdetail?partno=GRM155R61H104KE14%23"
			(at 0 0 270)
			(layer "F.Fab")
			(hide yes)
			(effects
				(font
					(size 1.27 1.27)
					(thickness 0.15)
				)
			)
		)
		(property "Author" "Antmicro"
			(at -73.333 287.835 0)
			(layer "F.Fab")
			(hide yes)
			(effects
				(font
					(size 1 1)
					(thickness 0.15)
				)
			)
		)
		(property "Dielectric" "X5R"
			(at -73.333 287.835 0)
			(layer "F.Fab")
			(hide yes)
			(effects
				(font
					(size 1 1)
					(thickness 0.15)
				)
			)
		)
		(property "License" "Apache-2.0"
			(at -73.333 287.835 0)
			(layer "F.Fab")
			(hide yes)
			(effects
				(font
					(size 1 1)
					(thickness 0.15)
				)
			)
		)
		(property "MPN" "GRM155R61H104KE14D"
			(at -73.333 287.835 0)
			(layer "F.Fab")
			(hide yes)
			(effects
				(font
					(size 1 1)
					(thickness 0.15)
				)
			)
		)
		(property "Manufacturer" "Murata"
			(at -73.333 287.835 0)
			(layer "F.Fab")
			(hide yes)
			(effects
				(font
					(size 1 1)
					(thickness 0.15)
				)
			)
		)
		(property "Val" "100n"
			(at -73.333 287.835 0)
			(layer "F.Fab")
			(hide yes)
			(effects
				(font
					(size 1 1)
					(thickness 0.15)
				)
			)
		)
		(property "Voltage" "50V"
			(at -73.333 287.835 0)
			(layer "F.Fab")
			(hide yes)
			(effects
				(font
					(size 1 1)
					(thickness 0.15)
				)
			)
		)
		(sheetname "/Debug FTDI/")
		(sheetfile "debug-ftdi.kicad_sch")
		(attr smd)
		(fp_rect
			(start -0.9659 -0.481258)
			(end 0.9649 0.458742)
			(stroke
				(width 0.05)
				(type solid)
			)
			(fill no)
			(layer "F.CrtYd")
		)
		(fp_line
			(start -0.499 0.248)
			(end -0.499 -0.25)
			(stroke
				(width 0.15)
				(type solid)
			)
			(layer "F.Fab")
		)
		(fp_line
			(start 0.499 0.248)
			(end -0.499 0.248)
			(stroke
				(width 0.15)
				(type solid)
			)
			(layer "F.Fab")
		)
		(fp_line
			(start -0.499 -0.25)
			(end 0.499 -0.25)
			(stroke
				(width 0.15)
				(type solid)
			)
			(layer "F.Fab")
		)
		(fp_line
			(start 0.499 -0.25)
			(end 0.499 0.248)
			(stroke
				(width 0.15)
				(type solid)
			)
			(layer "F.Fab")
		)
		(pad "1" smd roundrect
			(at -0.484 0 270)
			(size 0.59 0.64)
			(layers "F.Cu" "F.Mask" "F.Paste")
			(roundrect_rratio 0.25)
			(net 1 "GND")
			(pintype "passive")
		)
		(pad "2" smd roundrect
			(at 0.484 0 270)
			(size 0.59 0.64)
			(layers "F.Cu" "F.Mask" "F.Paste")
			(roundrect_rratio 0.25)
			(net 6 "/Debug FTDI/FTDI_3V3")
			(pintype "passive")
		)
	)
	(footprint "antmicro-footprints:USON-10_2.5x1mm_P0.5mm"
		(layer "F.Cu")
		(at 165.1 174.2 180)
		(descr "USON-10 2.5x1mm_ Pitch 0.5mm")
		(tags "USON-10 2.5x1mm Pitch 0.5mm")
		(property "Reference" "U2"
			(at 0.018 -1.7 180)
			(layer "F.SilkS")
			(hide yes)
			(effects
				(font
					(size 0.7 0.7)
					(thickness 0.15)
				)
				(justify left bottom)
			)
		)
		(property "Value" "TPD4E05U06QDQARQ1"
			(at 0.018 2.499 180)
			(layer "F.Fab")
			(effects
				(font
					(size 0.7 0.7)
					(thickness 0.15)
				)
				(justify left bottom)
			)
		)
		(property "Datasheet" "https://www.ti.com/lit/ds/symlink/tpd4e05u06-q1.pdf?HQS=dis-mous-null-mousermode-dsf-pf-null-wwe&ts=1663591265741&ref_url=https%253A%252F%252Fwww.mouser.com%252F"
			(at 0 0 180)
			(layer "F.Fab")
			(hide yes)
			(effects
				(font
					(size 1.27 1.27)
					(thickness 0.15)
				)
			)
		)
		(property "Author" "Antmicro"
			(at 330.2 348.4 0)
			(layer "F.Fab")
			(hide yes)
			(effects
				(font
					(size 1 1)
					(thickness 0.15)
				)
			)
		)
		(property "License" "Apache-2.0"
			(at 330.2 348.4 0)
			(layer "F.Fab")
			(hide yes)
			(effects
				(font
					(size 1 1)
					(thickness 0.15)
				)
			)
		)
		(property "MPN" "TPD4E05U06QDQARQ1"
			(at 330.2 348.4 0)
			(layer "F.Fab")
			(hide yes)
			(effects
				(font
					(size 1 1)
					(thickness 0.15)
				)
			)
		)
		(property "Manufacturer" "Texas Instruments"
			(at 330.2 348.4 0)
			(layer "F.Fab")
			(hide yes)
			(effects
				(font
					(size 1 1)
					(thickness 0.15)
				)
			)
		)
		(sheetname "/FPGA Config/")
		(sheetfile "fpga-config.kicad_sch")
		(attr exclude_from_pos_files exclude_from_bom dnp)
		(fp_line
			(start 0.498 1.398)
			(end -0.5 1.398)
			(stroke
				(width 0.15)
				(type solid)
			)
			(layer "F.SilkS")
		)
		(fp_line
			(start 0.498 -1.401)
			(end -0.5 -1.401)
			(stroke
				(width 0.15)
				(type solid)
			)
			(layer "F.SilkS")
		)
		(fp_circle
			(center -0.68 -1.27)
			(end -0.63 -1.27)
			(stroke
				(width 0.15)
				(type solid)
			)
			(fill yes)
			(layer "F.SilkS")
		)
		(fp_rect
			(start -0.8 -1.5)
			(end 0.8 1.499)
			(stroke
				(width 0.05)
				(type solid)
			)
			(fill no)
			(layer "F.CrtYd")
		)
		(fp_line
			(start 0.498 -1.25)
			(end 0.498 1.249)
			(stroke
				(width 0.15)
				(type solid)
			)
			(layer "F.Fab")
		)
		(fp_line
			(start 0.498 -1.25)
			(end -0.25 -1.25)
			(stroke
				(width 0.15)
				(type solid)
			)
			(layer "F.Fab")
		)
		(fp_line
			(start -0.25 -1.25)
			(end -0.5 -1)
			(stroke
				(width 0.15)
				(type solid)
			)
			(layer "F.Fab")
		)
		(fp_line
			(start -0.5 1.249)
			(end 0.498 1.249)
			(stroke
				(width 0.15)
				(type solid)
			)
			(layer "F.Fab")
		)
		(fp_line
			(start -0.5 -1)
			(end -0.5 1.249)
			(stroke
				(width 0.15)
				(type solid)
			)
			(layer "F.Fab")
		)
		(pad "1" smd roundrect
			(at -0.387 -1 90)
			(size 0.25 0.55)
			(layers "F.Cu" "F.Mask" "F.Paste")
			(roundrect_rratio 0.25)
			(net 45 "/Debug FTDI/JTAG.TMS")
			(pintype "passive")
		)
		(pad "2" smd roundrect
			(at -0.387 -0.5 90)
			(size 0.25 0.55)
			(layers "F.Cu" "F.Mask" "F.Paste")
			(roundrect_rratio 0.25)
			(net 46 "/Debug FTDI/JTAG.TCK")
			(pintype "passive")
		)
		(pad "3" smd roundrect
			(at -0.387 0 90)
			(size 0.4 0.55)
			(layers "F.Cu" "F.Mask" "F.Paste")
			(roundrect_rratio 0.25)
			(net 1 "GND")
			(pintype "power_in")
		)
		(pad "4" smd roundrect
			(at -0.387 0.498 90)
			(size 0.25 0.55)
			(layers "F.Cu" "F.Mask" "F.Paste")
			(roundrect_rratio 0.25)
			(net 47 "/Debug FTDI/JTAG.TDO")
			(pintype "passive")
		)
		(pad "5" smd roundrect
			(at -0.387 0.998 90)
			(size 0.25 0.55)
			(layers "F.Cu" "F.Mask" "F.Paste")
			(roundrect_rratio 0.25)
			(net 48 "/Debug FTDI/JTAG.TDI")
			(pintype "passive")
		)
		(pad "6" smd roundrect
			(at 0.385 0.998 90)
			(size 0.25 0.55)
			(layers "F.Cu" "F.Mask" "F.Paste")
			(roundrect_rratio 0.25)
			(net 48 "/Debug FTDI/JTAG.TDI")
			(pintype "passive")
		)
		(pad "7" smd roundrect
			(at 0.385 0.498 90)
			(size 0.25 0.55)
			(layers "F.Cu" "F.Mask" "F.Paste")
			(roundrect_rratio 0.25)
			(net 47 "/Debug FTDI/JTAG.TDO")
			(pintype "passive")
		)
		(pad "8" smd roundrect
			(at 0.385 0 90)
			(size 0.4 0.55)
			(layers "F.Cu" "F.Mask" "F.Paste")
			(roundrect_rratio 0.25)
			(net 1 "GND")
			(pintype "passive")
		)
		(pad "9" smd roundrect
			(at 0.385 -0.5 90)
			(size 0.25 0.55)
			(layers "F.Cu" "F.Mask" "F.Paste")
			(roundrect_rratio 0.25)
			(net 46 "/Debug FTDI/JTAG.TCK")
			(pintype "passive")
		)
		(pad "10" smd roundrect
			(at 0.385 -1 90)
			(size 0.25 0.55)
			(layers "F.Cu" "F.Mask" "F.Paste")
			(roundrect_rratio 0.25)
			(net 45 "/Debug FTDI/JTAG.TMS")
			(pintype "passive")
		)
	)
)
